(kicad_pcb
	(version 20241229)
	(generator "pcbnew")
	(generator_version "9.0")
	(general
		(thickness 1.552)
		(legacy_teardrops no)
	)
	(paper "A4")
	(title_block
		(date "2023-07-25")
		(rev "1.1.4")
		(comment 9 "footprints 332-336 of 379")
	)
	(layers
		(0 "F.Cu" signal)
		(4 "In1.Cu" signal)
		(6 "In2.Cu" signal)
		(8 "In3.Cu" signal)
		(10 "In4.Cu" signal)
		(12 "In5.Cu" signal)
		(14 "In6.Cu" signal)
		(2 "B.Cu" signal)
		(9 "F.Adhes" user "F.Adhesive")
		(11 "B.Adhes" user "B.Adhesive")
		(13 "F.Paste" user)
		(15 "B.Paste" user)
		(5 "F.SilkS" user "F.Silkscreen")
		(7 "B.SilkS" user "B.Silkscreen")
		(1 "F.Mask" user)
		(3 "B.Mask" user)
		(17 "Dwgs.User" user "User.Drawings")
		(19 "Cmts.User" user "User.Comments")
		(21 "Eco1.User" user "User.Eco1")
		(23 "Eco2.User" user "User.Eco2")
		(25 "Edge.Cuts" user)
		(27 "Margin" user)
		(31 "F.CrtYd" user "F.Courtyard")
		(29 "B.CrtYd" user "B.Courtyard")
		(35 "F.Fab" user)
		(33 "B.Fab" user)
	)
	(footprint "antmicro-footprints:C_0402_1005Metric"
		(layer "B.Cu")
		(at 120.45 66.13 90)
		(descr "Capacitor SMD 0402")
		(tags "capacitor SMD 0402")
		(property "Reference" "C46"
			(at -0.91 -0.72 90)
			(layer "B.SilkS")
			(effects
				(font
					(size 0.65 0.65)
					(thickness 0.15)
				)
				(justify right bottom mirror)
			)
		)
		(property "Value" "C_100n_0402"
			(at 0 -1.4 90)
			(layer "B.Fab")
			(hide yes)
			(effects
				(font
					(size 0.7 0.7)
					(thickness 0.15)
				)
				(justify right bottom mirror)
			)
		)
		(property "Datasheet" "https://www.murata.com/products/productdetail?partno=GRM155R61H104KE14%23"
			(at 0 0 90)
			(layer "F.Fab")
			(hide yes)
			(effects
				(font
					(size 1.27 1.27)
					(thickness 0.15)
				)
			)
		)
		(property "Description" "SMD Multilayer Ceramic Capacitor, 0.1 µF, 50 V, 0402 [1005 Metric], ± 10%, X5R, GRM Series"
			(at 0 0 90)
			(layer "F.Fab")
			(hide yes)
			(effects
				(font
					(size 1.27 1.27)
					(thickness 0.15)
				)
			)
		)
		(property "Author" "Antmicro"
			(at 186.58 -54.32 0)
			(layer "B.Fab")
			(hide yes)
			(effects
				(font
					(size 1 1)
					(thickness 0.15)
				)
				(justify mirror)
			)
		)
		(property "Dielectric" "X5R"
			(at 186.58 -54.32 0)
			(layer "B.Fab")
			(hide yes)
			(effects
				(font
					(size 1 1)
					(thickness 0.15)
				)
				(justify mirror)
			)
		)
		(property "License" "Apache-2.0"
			(at 186.58 -54.32 0)
			(layer "B.Fab")
			(hide yes)
			(effects
				(font
					(size 1 1)
					(thickness 0.15)
				)
				(justify mirror)
			)
		)
		(property "MPN" "GRM155R61H104KE14D"
			(at 186.58 -54.32 0)
			(layer "B.Fab")
			(hide yes)
			(effects
				(font
					(size 1 1)
					(thickness 0.15)
				)
				(justify mirror)
			)
		)
		(property "Manufacturer" "Murata"
			(at 186.58 -54.32 0)
			(layer "B.Fab")
			(hide yes)
			(effects
				(font
					(size 1 1)
					(thickness 0.15)
				)
				(justify mirror)
			)
		)
		(property "Val" "100n"
			(at 186.58 -54.32 0)
			(layer "B.Fab")
			(hide yes)
			(effects
				(font
					(size 1 1)
					(thickness 0.15)
				)
				(justify mirror)
			)
		)
		(property "Voltage" "50V"
			(at 186.58 -54.32 0)
			(layer "B.Fab")
			(hide yes)
			(effects
				(font
					(size 1 1)
					(thickness 0.15)
				)
				(justify mirror)
			)
		)
		(sheetname "/DDR3/")
		(sheetfile "ddr3.kicad_sch")
		(attr smd)
		(fp_rect
			(start -0.925 0.47)
			(end 0.925 -0.47)
			(stroke
				(width 0.05)
				(type default)
			)
			(fill no)
			(layer "B.CrtYd")
		)
		(fp_line
			(start 0.504 -0.248)
			(end -0.494 -0.248)
			(stroke
				(width 0.15)
				(type solid)
			)
			(layer "B.Fab")
		)
		(fp_line
			(start -0.494 -0.248)
			(end -0.494 0.25)
			(stroke
				(width 0.15)
				(type solid)
			)
			(layer "B.Fab")
		)
		(fp_line
			(start 0.504 0.25)
			(end 0.504 -0.248)
			(stroke
				(width 0.15)
				(type solid)
			)
			(layer "B.Fab")
		)
		(fp_line
			(start -0.494 0.25)
			(end 0.504 0.25)
			(stroke
				(width 0.15)
				(type solid)
			)
			(layer "B.Fab")
		)
		(fp_text user "License: Apache-2.0"
			(at -0.939 -5.799 270)
			(layer "B.Fab")
			(effects
				(font
					(size 0.7 0.7)
					(thickness 0.15)
				)
				(justify left bottom mirror)
			)
		)
		(fp_text user "Author: Antmicro"
			(at -0.939 -3.399 270)
			(layer "B.Fab")
			(effects
				(font
					(size 0.7 0.7)
					(thickness 0.15)
				)
				(justify left bottom mirror)
			)
		)
		(fp_text user "${REFERENCE}"
			(at -0.939 -4.599 270)
			(layer "B.Fab")
			(effects
				(font
					(size 0.7 0.7)
					(thickness 0.15)
				)
				(justify left bottom mirror)
			)
		)
		(pad "1" smd roundrect
			(at -0.48 0 90)
			(size 0.59 0.64)
			(layers "B.Cu" "B.Mask" "B.Paste")
			(roundrect_rratio 0.25)
			(net 1 "GND")
			(pintype "passive")
		)
		(pad "2" smd roundrect
			(at 0.48 0 90)
			(size 0.59 0.64)
			(layers "B.Cu" "B.Mask" "B.Paste")
			(roundrect_rratio 0.25)
			(net 248 "+1V5")
			(pintype "passive")
		)
	)
	(footprint "antmicro-footprints:C_0201"
		(layer "B.Cu")
		(at 125.9 94.3 180)
		(descr "Capacitor SMD 0201")
		(tags "capacitor SMD 0201")
		(property "Reference" "C107"
			(at 8.27 12.295736 0)
			(layer "B.SilkS")
			(effects
				(font
					(size 0.65 0.65)
					(thickness 0.15)
				)
				(justify left bottom mirror)
			)
		)
		(property "Value" "C_100n_0201"
			(at 0 -1.4 0)
			(layer "B.Fab")
			(hide yes)
			(effects
				(font
					(size 0.7 0.7)
					(thickness 0.15)
				)
				(justify left bottom mirror)
			)
		)
		(property "Datasheet" "https://www.yageo.com/en/Chart/Download/pdf/CC0201KRX6S5BB104"
			(at 0 0 180)
			(layer "F.Fab")
			(hide yes)
			(effects
				(font
					(size 1.27 1.27)
					(thickness 0.15)
				)
			)
		)
		(property "Description" "SMD Multilayer Ceramic Capacitor, 0.1 µF, 6.3 V, 0201 [0603 Metric], ± 10%, X6S, CC Series"
			(at 0 0 180)
			(layer "F.Fab")
			(hide yes)
			(effects
				(font
					(size 1.27 1.27)
					(thickness 0.15)
				)
			)
		)
		(property "Author" "Antmicro"
			(at 251.8 188.6 0)
			(layer "B.Fab")
			(hide yes)
			(effects
				(font
					(size 1 1)
					(thickness 0.15)
				)
				(justify mirror)
			)
		)
		(property "Dielectric" ""
			(at 251.8 188.6 0)
			(layer "B.Fab")
			(hide yes)
			(effects
				(font
					(size 1 1)
					(thickness 0.15)
				)
				(justify mirror)
			)
		)
		(property "License" "Apache-2.0"
			(at 251.8 188.6 0)
			(layer "B.Fab")
			(hide yes)
			(effects
				(font
					(size 1 1)
					(thickness 0.15)
				)
				(justify mirror)
			)
		)
		(property "MPN" "CC0201KRX6S5BB104"
			(at 251.8 188.6 0)
			(layer "B.Fab")
			(hide yes)
			(effects
				(font
					(size 1 1)
					(thickness 0.15)
				)
				(justify mirror)
			)
		)
		(property "Manufacturer" "YAGEO"
			(at 251.8 188.6 0)
			(layer "B.Fab")
			(hide yes)
			(effects
				(font
					(size 1 1)
					(thickness 0.15)
				)
				(justify mirror)
			)
		)
		(property "Val" "100n"
			(at 251.8 188.6 0)
			(layer "B.Fab")
			(hide yes)
			(effects
				(font
					(size 1 1)
					(thickness 0.15)
				)
				(justify mirror)
			)
		)
		(property "Voltage" ""
			(at 251.8 188.6 0)
			(layer "B.Fab")
			(hide yes)
			(effects
				(font
					(size 1 1)
					(thickness 0.15)
				)
				(justify mirror)
			)
		)
		(property "Public" "False"
			(at 0 0 180)
			(unlocked yes)
			(layer "B.Fab")
			(hide yes)
			(effects
				(font
					(size 1 1)
					(thickness 0.15)
				)
				(justify mirror)
			)
		)
		(sheetname "/FPGA Power/")
		(sheetfile "FPGA_Power.kicad_sch")
		(attr smd)
		(fp_rect
			(start -0.7 0.35)
			(end 0.7 -0.35)
			(stroke
				(width 0.05)
				(type default)
			)
			(fill no)
			(layer "B.CrtYd")
		)
		(fp_rect
			(start 0.3 -0.15)
			(end -0.301 0.149)
			(stroke
				(width 0.15)
				(type solid)
			)
			(fill no)
			(layer "B.Fab")
		)
		(fp_text user "Author: Antmicro"
			(at -0.72 -5.4 0)
			(layer "B.Fab")
			(effects
				(font
					(size 0.7 0.7)
					(thickness 0.15)
				)
				(justify left bottom mirror)
			)
		)
		(fp_text user "License: Apache-2.0"
			(at -0.72 -4.4 0)
			(layer "B.Fab")
			(effects
				(font
					(size 0.7 0.7)
					(thickness 0.15)
				)
				(justify left bottom mirror)
			)
		)
		(fp_text user "${REFERENCE}"
			(at -0.72 -3.4 0)
			(layer "B.Fab")
			(effects
				(font
					(size 0.7 0.7)
					(thickness 0.15)
				)
				(justify left bottom mirror)
			)
		)
		(pad "" smd roundrect
			(at -0.349 0.002 180)
			(size 0.318 0.36)
			(layers "B.Paste")
			(roundrect_rratio 0.25)
		)
		(pad "" smd roundrect
			(at 0.341 0.002 180)
			(size 0.318 0.36)
			(layers "B.Paste")
			(roundrect_rratio 0.25)
		)
		(pad "1" smd roundrect
			(at -0.321 0.002 180)
			(size 0.46 0.4)
			(layers "B.Cu" "B.Mask")
			(roundrect_rratio 0.25)
			(net 1 "GND")
			(pintype "passive")
		)
		(pad "2" smd roundrect
			(at 0.32 0.002 180)
			(size 0.46 0.4)
			(layers "B.Cu" "B.Mask")
			(roundrect_rratio 0.25)
			(net 4 "1V0_Power")
			(pintype "passive")
		)
	)
	(footprint "antmicro-footprints:R_0402_1005Metric"
		(layer "B.Cu")
		(at 104.89 91.8 -90)
		(descr "Resistor SMD 0402")
		(tags "resistor SMD 0402")
		(property "Reference" "R83"
			(at 1.04 0.66 90)
			(layer "B.SilkS")
			(effects
				(font
					(size 0.65 0.65)
					(thickness 0.15)
				)
				(justify left bottom mirror)
			)
		)
		(property "Value" "R_4k7_0402"
			(at 0 -1.4 90)
			(layer "B.Fab")
			(hide yes)
			(effects
				(font
					(size 0.7 0.7)
					(thickness 0.15)
				)
				(justify left bottom mirror)
			)
		)
		(property "Datasheet" "https://www.bourns.com/docs/product-datasheets/cr.pdf"
			(at 0 0 270)
			(layer "F.Fab")
			(hide yes)
			(effects
				(font
					(size 1.27 1.27)
					(thickness 0.15)
				)
			)
		)
		(property "Description" "SMD Chip Resistor, 4.7 kohm, ± 1%, 62.5 mW, 0402 [1005 Metric], Thick Film, General Purpose"
			(at 0 0 270)
			(layer "F.Fab")
			(hide yes)
			(effects
				(font
					(size 1.27 1.27)
					(thickness 0.15)
				)
			)
		)
		(property "Author" "Antmicro"
			(at 13.09 196.69 0)
			(layer "B.Fab")
			(hide yes)
			(effects
				(font
					(size 1 1)
					(thickness 0.15)
				)
				(justify mirror)
			)
		)
		(property "License" "Apache-2.0"
			(at 13.09 196.69 0)
			(layer "B.Fab")
			(hide yes)
			(effects
				(font
					(size 1 1)
					(thickness 0.15)
				)
				(justify mirror)
			)
		)
		(property "MPN" "CR0402-FX-4701GLF"
			(at 13.09 196.69 0)
			(layer "B.Fab")
			(hide yes)
			(effects
				(font
					(size 1 1)
					(thickness 0.15)
				)
				(justify mirror)
			)
		)
		(property "Manufacturer" "Bourns"
			(at 13.09 196.69 0)
			(layer "B.Fab")
			(hide yes)
			(effects
				(font
					(size 1 1)
					(thickness 0.15)
				)
				(justify mirror)
			)
		)
		(property "Tolerance" "1%"
			(at 13.09 196.69 0)
			(layer "B.Fab")
			(hide yes)
			(effects
				(font
					(size 1 1)
					(thickness 0.15)
				)
				(justify mirror)
			)
		)
		(property "Val" "4k7"
			(at 13.09 196.69 0)
			(layer "B.Fab")
			(hide yes)
			(effects
				(font
					(size 1 1)
					(thickness 0.15)
				)
				(justify mirror)
			)
		)
		(sheetname "/FPGA/")
		(sheetfile "fpga.kicad_sch")
		(attr smd)
		(fp_rect
			(start -0.925 0.47)
			(end 0.925 -0.47)
			(stroke
				(width 0.05)
				(type default)
			)
			(fill no)
			(layer "B.CrtYd")
		)
		(fp_rect
			(start -0.5 0.25)
			(end 0.5 -0.25)
			(stroke
				(width 0.15)
				(type solid)
			)
			(fill no)
			(layer "B.Fab")
		)
		(fp_text user "${REFERENCE}"
			(at -0.95 -3.168 90)
			(layer "B.Fab")
			(effects
				(font
					(size 0.7 0.7)
					(thickness 0.15)
				)
				(justify left bottom mirror)
			)
		)
		(fp_text user "License: Apache-2.0"
			(at -0.95 -5.169 90)
			(layer "B.Fab")
			(effects
				(font
					(size 0.7 0.7)
					(thickness 0.15)
				)
				(justify left bottom mirror)
			)
		)
		(fp_text user "Author: Antmicro"
			(at -0.95 -4.169 90)
			(layer "B.Fab")
			(effects
				(font
					(size 0.7 0.7)
					(thickness 0.15)
				)
				(justify left bottom mirror)
			)
		)
		(pad "1" smd roundrect
			(at -0.48 0 270)
			(size 0.59 0.64)
			(layers "B.Cu" "B.Mask" "B.Paste")
			(roundrect_rratio 0.25)
			(net 2 "+3V3")
			(pintype "passive")
		)
		(pad "2" smd roundrect
			(at 0.48 0 270)
			(size 0.59 0.64)
			(layers "B.Cu" "B.Mask" "B.Paste")
			(roundrect_rratio 0.25)
			(net 28 "/FPGA/SPI_DQ2")
			(pintype "passive")
		)
	)
	(footprint "antmicro-footprints:C_0402_1005Metric"
		(layer "B.Cu")
		(at 89.3 80.4)
		(descr "Capacitor SMD 0402")
		(tags "capacitor SMD 0402")
		(property "Reference" "C62"
			(at -0.97 1.34 0)
			(layer "B.SilkS")
			(effects
				(font
					(size 0.65 0.65)
					(thickness 0.15)
				)
				(justify right bottom mirror)
			)
		)
		(property "Value" "C_100n_0402"
			(at 0 -1.4 0)
			(layer "B.Fab")
			(hide yes)
			(effects
				(font
					(size 0.7 0.7)
					(thickness 0.15)
				)
				(justify right bottom mirror)
			)
		)
		(property "Datasheet" "https://www.murata.com/products/productdetail?partno=GRM155R61H104KE14%23"
			(at 0 0 0)
			(layer "F.Fab")
			(hide yes)
			(effects
				(font
					(size 1.27 1.27)
					(thickness 0.15)
				)
			)
		)
		(property "Description" "SMD Multilayer Ceramic Capacitor, 0.1 µF, 50 V, 0402 [1005 Metric], ± 10%, X5R, GRM Series"
			(at 0 0 0)
			(layer "F.Fab")
			(hide yes)
			(effects
				(font
					(size 1.27 1.27)
					(thickness 0.15)
				)
			)
		)
		(property "Author" "Antmicro"
			(at 0 0 0)
			(layer "B.Fab")
			(hide yes)
			(effects
				(font
					(size 1 1)
					(thickness 0.15)
				)
				(justify mirror)
			)
		)
		(property "Dielectric" "X5R"
			(at 0 0 0)
			(layer "B.Fab")
			(hide yes)
			(effects
				(font
					(size 1 1)
					(thickness 0.15)
				)
				(justify mirror)
			)
		)
		(property "License" "Apache-2.0"
			(at 0 0 0)
			(layer "B.Fab")
			(hide yes)
			(effects
				(font
					(size 1 1)
					(thickness 0.15)
				)
				(justify mirror)
			)
		)
		(property "MPN" "GRM155R61H104KE14D"
			(at 0 0 0)
			(layer "B.Fab")
			(hide yes)
			(effects
				(font
					(size 1 1)
					(thickness 0.15)
				)
				(justify mirror)
			)
		)
		(property "Manufacturer" "Murata"
			(at 0 0 0)
			(layer "B.Fab")
			(hide yes)
			(effects
				(font
					(size 1 1)
					(thickness 0.15)
				)
				(justify mirror)
			)
		)
		(property "Val" "100n"
			(at 0 0 0)
			(layer "B.Fab")
			(hide yes)
			(effects
				(font
					(size 1 1)
					(thickness 0.15)
				)
				(justify mirror)
			)
		)
		(property "Voltage" "50V"
			(at 0 0 0)
			(layer "B.Fab")
			(hide yes)
			(effects
				(font
					(size 1 1)
					(thickness 0.15)
				)
				(justify mirror)
			)
		)
		(sheetname "/SDI/")
		(sheetfile "sdi.kicad_sch")
		(attr smd)
		(fp_rect
			(start -0.925 0.47)
			(end 0.925 -0.47)
			(stroke
				(width 0.05)
				(type default)
			)
			(fill no)
			(layer "B.CrtYd")
		)
		(fp_line
			(start -0.494 -0.248)
			(end -0.494 0.25)
			(stroke
				(width 0.15)
				(type solid)
			)
			(layer "B.Fab")
		)
		(fp_line
			(start -0.494 0.25)
			(end 0.504 0.25)
			(stroke
				(width 0.15)
				(type solid)
			)
			(layer "B.Fab")
		)
		(fp_line
			(start 0.504 -0.248)
			(end -0.494 -0.248)
			(stroke
				(width 0.15)
				(type solid)
			)
			(layer "B.Fab")
		)
		(fp_line
			(start 0.504 0.25)
			(end 0.504 -0.248)
			(stroke
				(width 0.15)
				(type solid)
			)
			(layer "B.Fab")
		)
		(fp_text user "License: Apache-2.0"
			(at -0.939 -5.799 180)
			(layer "B.Fab")
			(effects
				(font
					(size 0.7 0.7)
					(thickness 0.15)
				)
				(justify left bottom mirror)
			)
		)
		(fp_text user "${REFERENCE}"
			(at -0.939 -4.599 180)
			(layer "B.Fab")
			(effects
				(font
					(size 0.7 0.7)
					(thickness 0.15)
				)
				(justify left bottom mirror)
			)
		)
		(fp_text user "Author: Antmicro"
			(at -0.939 -3.399 180)
			(layer "B.Fab")
			(effects
				(font
					(size 0.7 0.7)
					(thickness 0.15)
				)
				(justify left bottom mirror)
			)
		)
		(pad "1" smd roundrect
			(at -0.48 0)
			(size 0.59 0.64)
			(layers "B.Cu" "B.Mask" "B.Paste")
			(roundrect_rratio 0.25)
			(net 1 "GND")
			(pintype "passive")
		)
		(pad "2" smd roundrect
			(at 0.48 0)
			(size 0.59 0.64)
			(layers "B.Cu" "B.Mask" "B.Paste")
			(roundrect_rratio 0.25)
			(net 2 "+3V3")
			(pintype "passive")
		)
	)
	(footprint "antmicro-footprints:R_0402_1005Metric"
		(layer "B.Cu")
		(at 103.89 91.8 90)
		(descr "Resistor SMD 0402")
		(tags "resistor SMD 0402")
		(property "Reference" "R87"
			(at -1.04 1.34 270)
			(layer "B.SilkS")
			(effects
				(font
					(size 0.65 0.65)
					(thickness 0.15)
				)
				(justify left bottom mirror)
			)
		)
		(property "Value" "R_4k7_0402"
			(at 0 -1.4 270)
			(layer "B.Fab")
			(hide yes)
			(effects
				(font
					(size 0.7 0.7)
					(thickness 0.15)
				)
				(justify left bottom mirror)
			)
		)
		(property "Datasheet" "https://www.bourns.com/docs/product-datasheets/cr.pdf"
			(at 0 0 90)
			(layer "F.Fab")
			(hide yes)
			(effects
				(font
					(size 1.27 1.27)
					(thickness 0.15)
				)
			)
		)
		(property "Description" "SMD Chip Resistor, 4.7 kohm, ± 1%, 62.5 mW, 0402 [1005 Metric], Thick Film, General Purpose"
			(at 0 0 90)
			(layer "F.Fab")
			(hide yes)
			(effects
				(font
					(size 1.27 1.27)
					(thickness 0.15)
				)
			)
		)
		(property "Author" "Antmicro"
			(at 195.69 -12.09 0)
			(layer "B.Fab")
			(hide yes)
			(effects
				(font
					(size 1 1)
					(thickness 0.15)
				)
				(justify mirror)
			)
		)
		(property "License" "Apache-2.0"
			(at 195.69 -12.09 0)
			(layer "B.Fab")
			(hide yes)
			(effects
				(font
					(size 1 1)
					(thickness 0.15)
				)
				(justify mirror)
			)
		)
		(property "MPN" "CR0402-FX-4701GLF"
			(at 195.69 -12.09 0)
			(layer "B.Fab")
			(hide yes)
			(effects
				(font
					(size 1 1)
					(thickness 0.15)
				)
				(justify mirror)
			)
		)
		(property "Manufacturer" "Bourns"
			(at 195.69 -12.09 0)
			(layer "B.Fab")
			(hide yes)
			(effects
				(font
					(size 1 1)
					(thickness 0.15)
				)
				(justify mirror)
			)
		)
		(property "Tolerance" "1%"
			(at 195.69 -12.09 0)
			(layer "B.Fab")
			(hide yes)
			(effects
				(font
					(size 1 1)
					(thickness 0.15)
				)
				(justify mirror)
			)
		)
		(property "Val" "4k7"
			(at 195.69 -12.09 0)
			(layer "B.Fab")
			(hide yes)
			(effects
				(font
					(size 1 1)
					(thickness 0.15)
				)
				(justify mirror)
			)
		)
		(sheetname "/FPGA/")
		(sheetfile "fpga.kicad_sch")
		(attr smd)
		(fp_rect
			(start -0.925 0.47)
			(end 0.925 -0.47)
			(stroke
				(width 0.05)
				(type default)
			)
			(fill no)
			(layer "B.CrtYd")
		)
		(fp_rect
			(start -0.5 0.25)
			(end 0.5 -0.25)
			(stroke
				(width 0.15)
				(type solid)
			)
			(fill no)
			(layer "B.Fab")
		)
		(fp_text user "Author: Antmicro"
			(at -0.95 -4.169 270)
			(layer "B.Fab")
			(effects
				(font
					(size 0.7 0.7)
					(thickness 0.15)
				)
				(justify left bottom mirror)
			)
		)
		(fp_text user "${REFERENCE}"
			(at -0.95 -3.168 270)
			(layer "B.Fab")
			(effects
				(font
					(size 0.7 0.7)
					(thickness 0.15)
				)
				(justify left bottom mirror)
			)
		)
		(fp_text user "License: Apache-2.0"
			(at -0.95 -5.169 270)
			(layer "B.Fab")
			(effects
				(font
					(size 0.7 0.7)
					(thickness 0.15)
				)
				(justify left bottom mirror)
			)
		)
		(pad "1" smd roundrect
			(at -0.48 0 90)
			(size 0.59 0.64)
			(layers "B.Cu" "B.Mask" "B.Paste")
			(roundrect_rratio 0.25)
			(net 27 "/FPGA/SPI_DQ3")
			(pintype "passive")
		)
		(pad "2" smd roundrect
			(at 0.48 0 90)
			(size 0.59 0.64)
			(layers "B.Cu" "B.Mask" "B.Paste")
			(roundrect_rratio 0.25)
			(net 2 "+3V3")
			(pintype "passive")
		)
	)
)
